# S9S_MB_2U (Grand Teton) — schematic netlist excerpt (pin names and nets, part order shuffled) for the footprints in the layout excerpt that follows; sources: Cadence DE-HDL packaged netlist, KiCad conversion of 03242023_DA0F0TMBIJ0_F0T_Motherboard_J_brd_V01_OCP.brd

C1042  Q_CAP  100NF 50V 10% X7R  pkg C0402  page 260 : A = P5V_AUX ; B = GND

(kicad_pcb
	(version 20260206)
	(generator "pcbnew")
	(generator_version "10.0")
	(general
		(thickness 1.6)
		(legacy_teardrops no)
	)
	(paper "A4")
	(title_block
		(title "03242023_DA0F0TMBIJ0_F0T_Motherboard_J_brd_V01_OCP.brd")
		(comment 1 "Grand Teton / footprints 1197-1197 of 6105")
	)
	(layers
		(0 "F.Cu" signal "TOP")
		(4 "In1.Cu" signal "GND")
		(6 "In2.Cu" signal "IN1")
		(8 "In3.Cu" signal "GND1")
		(10 "In4.Cu" signal "IN2")
		(12 "In5.Cu" signal "GND2")
		(14 "In6.Cu" signal "IN3")
		(16 "In7.Cu" signal "GND3")
		(18 "In8.Cu" signal "VCC")
		(20 "In9.Cu" signal "VCC1")
		(22 "In10.Cu" signal "GND4")
		(24 "In11.Cu" signal "IN4")
		(26 "In12.Cu" signal "GND5")
		(28 "In13.Cu" signal "IN5")
		(30 "In14.Cu" signal "GND6")
		(32 "In15.Cu" signal "IN6")
		(34 "In16.Cu" signal "GND7")
		(2 "B.Cu" signal "BOTTOM")
		(9 "F.Adhes" user "F.Adhesive")
		(11 "B.Adhes" user "B.Adhesive")
		(13 "F.Paste" user "Package Geometry/Pastemask Top")
		(15 "B.Paste" user "Package Geometry/Pastemask Bottom")
		(5 "F.SilkS" user "Ref Des/Silkscreen Top")
		(7 "B.SilkS" user "Ref Des/Silkscreen Bottom")
		(1 "F.Mask" user "Board Geometry/Soldermask Top")
		(3 "B.Mask" user "Board Geometry/Soldermask Bottom")
		(17 "Dwgs.User" user "User.Drawings")
		(19 "Cmts.User" user "User.Comments")
		(21 "Eco1.User" user "User.Eco1")
		(23 "Eco2.User" user "User.Eco2")
		(25 "Edge.Cuts" user "Board Geometry/Outline")
		(27 "Margin" user)
		(31 "F.CrtYd" user "Package Geometry/Place Bound Top")
		(29 "B.CrtYd" user "Package Geometry/Place Bound Bottom")
		(35 "F.Fab" user "Ref Des/Assembly Top")
		(33 "B.Fab" user "Ref Des/Assembly Bottom")
	)
	(footprint ""
		(layer "F.Cu")
		(at 446.03035 -374.891554)
		(property "Reference" "C1042"
			(at 0 0 0)
			(layer "F.SilkS")
			(hide yes)
			(effects
				(font
					(size 1.27 1.27)
				)
			)
		)
		(property "Value" ""
			(at 0 0 0)
			(layer "F.Fab")
			(effects
				(font
					(size 1.27 1.27)
				)
			)
		)
		(duplicate_pad_numbers_are_jumpers no)
		(fp_line
			(start -0.7874 -0.4064)
			(end 0.7874 -0.4064)
			(stroke
				(width 0.1524)
				(type default)
			)
			(layer "F.SilkS")
		)
		(fp_line
			(start -0.7874 0.4064)
			(end -0.7874 -0.4064)
			(stroke
				(width 0.1524)
				(type default)
			)
			(layer "F.SilkS")
		)
		(fp_line
			(start 0.7874 -0.4064)
			(end 0.7874 0.4064)
			(stroke
				(width 0.1524)
				(type default)
			)
			(layer "F.SilkS")
		)
		(fp_line
			(start 0.7874 0.4064)
			(end -0.7874 0.4064)
			(stroke
				(width 0.1524)
				(type default)
			)
			(layer "F.SilkS")
		)
		(fp_line
			(start -0.67945 -0.305054)
			(end -0.12065 -0.305054)
			(stroke
				(width 0.1)
				(type default)
			)
			(layer "F.Fab")
		)
		(fp_line
			(start -0.67945 0.3048)
			(end -0.67945 -0.305054)
			(stroke
				(width 0.1)
				(type default)
			)
			(layer "F.Fab")
		)
		(fp_line
			(start -0.12065 -0.305054)
			(end -0.12065 -0.2794)
			(stroke
				(width 0.1)
				(type default)
			)
			(layer "F.Fab")
		)
		(fp_line
			(start -0.12065 -0.2794)
			(end 0.12065 -0.2794)
			(stroke
				(width 0.1)
				(type default)
			)
			(layer "F.Fab")
		)
		(fp_line
			(start -0.12065 0.2794)
			(end -0.12065 0.3048)
			(stroke
				(width 0.1)
				(type default)
			)
			(layer "F.Fab")
		)
		(fp_line
			(start -0.12065 0.3048)
			(end -0.67945 0.3048)
			(stroke
				(width 0.1)
				(type default)
			)
			(layer "F.Fab")
		)
		(fp_line
			(start 0.120396 0.2794)
			(end -0.12065 0.2794)
			(stroke
				(width 0.1)
				(type default)
			)
			(layer "F.Fab")
		)
		(fp_line
			(start 0.120396 0.3048)
			(end 0.120396 0.2794)
			(stroke
				(width 0.1)
				(type default)
			)
			(layer "F.Fab")
		)
		(fp_line
			(start 0.12065 -0.3048)
			(end 0.67945 -0.3048)
			(stroke
				(width 0.1)
				(type default)
			)
			(layer "F.Fab")
		)
		(fp_line
			(start 0.12065 -0.2794)
			(end 0.12065 -0.3048)
			(stroke
				(width 0.1)
				(type default)
			)
			(layer "F.Fab")
		)
		(fp_line
			(start 0.67945 -0.3048)
			(end 0.67945 0.3048)
			(stroke
				(width 0.1)
				(type default)
			)
			(layer "F.Fab")
		)
		(fp_line
			(start 0.67945 0.3048)
			(end 0.120396 0.3048)
			(stroke
				(width 0.1)
				(type default)
			)
			(layer "F.Fab")
		)
		(pad "1" smd circle
			(at -0.40005 0)
			(size 0 0)
			(layers "F.Cu" "F.Mask" "F.Paste")
			(net "P5V_AUX")
		)
		(pad "2" smd circle
			(at 0.40005 0)
			(size 0 0)
			(layers "F.Cu" "F.Mask" "F.Paste")
			(net "GND")
		)
	)
)
